(kicad_pcb
	(version 20260206)
	(generator "pcbnew")
	(generator_version "10.0")
	(general
		(thickness 1.6)
		(legacy_teardrops no)
	)
	(paper "A4")
	(title_block
		(title "01162023_DA0F0TEBIF0_F0T_Expander_BD_F_brd_V02_OCP.brd")
		(comment 1 "Grand Teton / footprints 1830-1835 of 9728")
	)
	(layers
		(0 "F.Cu" signal "TOP")
		(4 "In1.Cu" signal "GND")
		(6 "In2.Cu" signal "VCC")
		(8 "In3.Cu" signal "VCC1")
		(10 "In4.Cu" signal "GND1")
		(12 "In5.Cu" signal "IN1")
		(14 "In6.Cu" signal "GND2")
		(16 "In7.Cu" signal "IN2")
		(18 "In8.Cu" signal "GND3")
		(20 "In9.Cu" signal "IN3")
		(22 "In10.Cu" signal "GND4")
		(24 "In11.Cu" signal "IN4")
		(26 "In12.Cu" signal "GND5")
		(28 "In13.Cu" signal "IN5")
		(30 "In14.Cu" signal "GND6")
		(32 "In15.Cu" signal "IN6")
		(34 "In16.Cu" signal "GND7")
		(2 "B.Cu" signal "BOTTOM")
		(9 "F.Adhes" user "F.Adhesive")
		(11 "B.Adhes" user "B.Adhesive")
		(13 "F.Paste" user "Package Geometry/Pastemask Top")
		(15 "B.Paste" user "Package Geometry/Pastemask Bottom")
		(5 "F.SilkS" user "Ref Des/Silkscreen Top")
		(7 "B.SilkS" user "Ref Des/Silkscreen Bottom")
		(1 "F.Mask" user "Board Geometry/Soldermask Top")
		(3 "B.Mask" user "Board Geometry/Soldermask Bottom")
		(17 "Dwgs.User" user "User.Drawings")
		(19 "Cmts.User" user "User.Comments")
		(21 "Eco1.User" user "User.Eco1")
		(23 "Eco2.User" user "User.Eco2")
		(25 "Edge.Cuts" user "Board Geometry/Outline")
		(27 "Margin" user)
		(31 "F.CrtYd" user "Package Geometry/Place Bound Top")
		(29 "B.CrtYd" user "Package Geometry/Place Bound Bottom")
		(35 "F.Fab" user "Ref Des/Assembly Top")
		(33 "B.Fab" user "Ref Des/Assembly Bottom")
	)
	(footprint ""
		(layer "F.Cu")
		(at 15.243302 -394.13053 90)
		(property "Reference" "R6842"
			(at 0 0 90)
			(layer "F.SilkS")
			(hide yes)
			(effects
				(font
					(size 1.27 1.27)
				)
			)
		)
		(property "Value" ""
			(at 0 0 90)
			(layer "F.Fab")
			(effects
				(font
					(size 1.27 1.27)
				)
			)
		)
		(duplicate_pad_numbers_are_jumpers no)
		(fp_line
			(start 0.7874 -0.4064)
			(end 0.7874 0.4064)
			(stroke
				(width 0.1524)
				(type default)
			)
			(layer "F.SilkS")
		)
		(fp_line
			(start -0.7874 -0.4064)
			(end 0.7874 -0.4064)
			(stroke
				(width 0.1524)
				(type default)
			)
			(layer "F.SilkS")
		)
		(fp_line
			(start 0.7874 0.4064)
			(end -0.7874 0.4064)
			(stroke
				(width 0.1524)
				(type default)
			)
			(layer "F.SilkS")
		)
		(fp_line
			(start -0.7874 0.4064)
			(end -0.7874 -0.4064)
			(stroke
				(width 0.1524)
				(type default)
			)
			(layer "F.SilkS")
		)
		(fp_line
			(start -0.12065 -0.305054)
			(end -0.12065 -0.2794)
			(stroke
				(width 0.1)
				(type default)
			)
			(layer "F.Fab")
		)
		(fp_line
			(start -0.67945 -0.305054)
			(end -0.12065 -0.305054)
			(stroke
				(width 0.1)
				(type default)
			)
			(layer "F.Fab")
		)
		(fp_line
			(start 0.67945 -0.3048)
			(end 0.67945 0.3048)
			(stroke
				(width 0.1)
				(type default)
			)
			(layer "F.Fab")
		)
		(fp_line
			(start 0.12065 -0.3048)
			(end 0.67945 -0.3048)
			(stroke
				(width 0.1)
				(type default)
			)
			(layer "F.Fab")
		)
		(fp_line
			(start 0.12065 -0.2794)
			(end 0.12065 -0.3048)
			(stroke
				(width 0.1)
				(type default)
			)
			(layer "F.Fab")
		)
		(fp_line
			(start -0.12065 -0.2794)
			(end 0.12065 -0.2794)
			(stroke
				(width 0.1)
				(type default)
			)
			(layer "F.Fab")
		)
		(fp_line
			(start 0.120396 0.2794)
			(end -0.12065 0.2794)
			(stroke
				(width 0.1)
				(type default)
			)
			(layer "F.Fab")
		)
		(fp_line
			(start -0.12065 0.2794)
			(end -0.12065 0.3048)
			(stroke
				(width 0.1)
				(type default)
			)
			(layer "F.Fab")
		)
		(fp_line
			(start 0.67945 0.3048)
			(end 0.120396 0.3048)
			(stroke
				(width 0.1)
				(type default)
			)
			(layer "F.Fab")
		)
		(fp_line
			(start 0.120396 0.3048)
			(end 0.120396 0.2794)
			(stroke
				(width 0.1)
				(type default)
			)
			(layer "F.Fab")
		)
		(fp_line
			(start -0.12065 0.3048)
			(end -0.67945 0.3048)
			(stroke
				(width 0.1)
				(type default)
			)
			(layer "F.Fab")
		)
		(fp_line
			(start -0.67945 0.3048)
			(end -0.67945 -0.305054)
			(stroke
				(width 0.1)
				(type default)
			)
			(layer "F.Fab")
		)
		(pad "1" smd circle
			(at -0.40005 0 90)
			(size 0 0)
			(layers "F.Cu" "F.Mask" "F.Paste")
			(net "BIC_USB_8042_HUB_FULLPWRMGMTZ")
		)
		(pad "2" smd circle
			(at 0.40005 0 90)
			(size 0 0)
			(layers "F.Cu" "F.Mask" "F.Paste")
			(net "P3V3_USB_HUB")
		)
	)
	(footprint ""
		(layer "F.Cu")
		(at 446.47485 -48.753014 180)
		(property "Reference" "C339"
			(at 0 0 180)
			(layer "F.SilkS")
			(hide yes)
			(effects
				(font
					(size 1.27 1.27)
				)
			)
		)
		(property "Value" ""
			(at 0 0 180)
			(layer "F.Fab")
			(effects
				(font
					(size 1.27 1.27)
				)
			)
		)
		(duplicate_pad_numbers_are_jumpers no)
		(fp_line
			(start 0.7874 0.4064)
			(end -0.7874 0.4064)
			(stroke
				(width 0.1524)
				(type default)
			)
			(layer "F.SilkS")
		)
		(fp_line
			(start 0.7874 -0.4064)
			(end 0.7874 0.4064)
			(stroke
				(width 0.1524)
				(type default)
			)
			(layer "F.SilkS")
		)
		(fp_line
			(start -0.7874 0.4064)
			(end -0.7874 -0.4064)
			(stroke
				(width 0.1524)
				(type default)
			)
			(layer "F.SilkS")
		)
		(fp_line
			(start -0.7874 -0.4064)
			(end 0.7874 -0.4064)
			(stroke
				(width 0.1524)
				(type default)
			)
			(layer "F.SilkS")
		)
		(fp_line
			(start 0.67945 0.3048)
			(end 0.120396 0.3048)
			(stroke
				(width 0.1)
				(type default)
			)
			(layer "F.Fab")
		)
		(fp_line
			(start 0.67945 -0.3048)
			(end 0.67945 0.3048)
			(stroke
				(width 0.1)
				(type default)
			)
			(layer "F.Fab")
		)
		(fp_line
			(start 0.12065 -0.2794)
			(end 0.12065 -0.3048)
			(stroke
				(width 0.1)
				(type default)
			)
			(layer "F.Fab")
		)
		(fp_line
			(start 0.12065 -0.3048)
			(end 0.67945 -0.3048)
			(stroke
				(width 0.1)
				(type default)
			)
			(layer "F.Fab")
		)
		(fp_line
			(start 0.120396 0.3048)
			(end 0.120396 0.2794)
			(stroke
				(width 0.1)
				(type default)
			)
			(layer "F.Fab")
		)
		(fp_line
			(start 0.120396 0.2794)
			(end -0.12065 0.2794)
			(stroke
				(width 0.1)
				(type default)
			)
			(layer "F.Fab")
		)
		(fp_line
			(start -0.12065 0.3048)
			(end -0.67945 0.3048)
			(stroke
				(width 0.1)
				(type default)
			)
			(layer "F.Fab")
		)
		(fp_line
			(start -0.12065 0.2794)
			(end -0.12065 0.3048)
			(stroke
				(width 0.1)
				(type default)
			)
			(layer "F.Fab")
		)
		(fp_line
			(start -0.12065 -0.2794)
			(end 0.12065 -0.2794)
			(stroke
				(width 0.1)
				(type default)
			)
			(layer "F.Fab")
		)
		(fp_line
			(start -0.12065 -0.305054)
			(end -0.12065 -0.2794)
			(stroke
				(width 0.1)
				(type default)
			)
			(layer "F.Fab")
		)
		(fp_line
			(start -0.67945 0.3048)
			(end -0.67945 -0.305054)
			(stroke
				(width 0.1)
				(type default)
			)
			(layer "F.Fab")
		)
		(fp_line
			(start -0.67945 -0.305054)
			(end -0.12065 -0.305054)
			(stroke
				(width 0.1)
				(type default)
			)
			(layer "F.Fab")
		)
		(pad "1" smd circle
			(at -0.40005 0 180)
			(size 0 0)
			(layers "F.Cu" "F.Mask" "F.Paste")
			(net "P3V3_AUX")
		)
		(pad "2" smd circle
			(at 0.40005 0 180)
			(size 0 0)
			(layers "F.Cu" "F.Mask" "F.Paste")
			(net "GND")
		)
	)
	(footprint ""
		(layer "F.Cu")
		(at 208.466436 -210.829652 180)
		(property "Reference" "R6296"
			(at 0 0 180)
			(layer "F.SilkS")
			(hide yes)
			(effects
				(font
					(size 1.27 1.27)
				)
			)
		)
		(property "Value" ""
			(at 0 0 180)
			(layer "F.Fab")
			(effects
				(font
					(size 1.27 1.27)
				)
			)
		)
		(duplicate_pad_numbers_are_jumpers no)
		(fp_line
			(start 0.7874 0.4064)
			(end -0.7874 0.4064)
			(stroke
				(width 0.1524)
				(type default)
			)
			(layer "F.SilkS")
		)
		(fp_line
			(start 0.7874 -0.4064)
			(end 0.7874 0.4064)
			(stroke
				(width 0.1524)
				(type default)
			)
			(layer "F.SilkS")
		)
		(fp_line
			(start -0.7874 0.4064)
			(end -0.7874 -0.4064)
			(stroke
				(width 0.1524)
				(type default)
			)
			(layer "F.SilkS")
		)
		(fp_line
			(start -0.7874 -0.4064)
			(end 0.7874 -0.4064)
			(stroke
				(width 0.1524)
				(type default)
			)
			(layer "F.SilkS")
		)
		(fp_line
			(start 0.67945 0.3048)
			(end 0.120396 0.3048)
			(stroke
				(width 0.1)
				(type default)
			)
			(layer "F.Fab")
		)
		(fp_line
			(start 0.67945 -0.3048)
			(end 0.67945 0.3048)
			(stroke
				(width 0.1)
				(type default)
			)
			(layer "F.Fab")
		)
		(fp_line
			(start 0.12065 -0.2794)
			(end 0.12065 -0.3048)
			(stroke
				(width 0.1)
				(type default)
			)
			(layer "F.Fab")
		)
		(fp_line
			(start 0.12065 -0.3048)
			(end 0.67945 -0.3048)
			(stroke
				(width 0.1)
				(type default)
			)
			(layer "F.Fab")
		)
		(fp_line
			(start 0.120396 0.3048)
			(end 0.120396 0.2794)
			(stroke
				(width 0.1)
				(type default)
			)
			(layer "F.Fab")
		)
		(fp_line
			(start 0.120396 0.2794)
			(end -0.12065 0.2794)
			(stroke
				(width 0.1)
				(type default)
			)
			(layer "F.Fab")
		)
		(fp_line
			(start -0.12065 0.3048)
			(end -0.67945 0.3048)
			(stroke
				(width 0.1)
				(type default)
			)
			(layer "F.Fab")
		)
		(fp_line
			(start -0.12065 0.2794)
			(end -0.12065 0.3048)
			(stroke
				(width 0.1)
				(type default)
			)
			(layer "F.Fab")
		)
		(fp_line
			(start -0.12065 -0.2794)
			(end 0.12065 -0.2794)
			(stroke
				(width 0.1)
				(type default)
			)
			(layer "F.Fab")
		)
		(fp_line
			(start -0.12065 -0.305054)
			(end -0.12065 -0.2794)
			(stroke
				(width 0.1)
				(type default)
			)
			(layer "F.Fab")
		)
		(fp_line
			(start -0.67945 0.3048)
			(end -0.67945 -0.305054)
			(stroke
				(width 0.1)
				(type default)
			)
			(layer "F.Fab")
		)
		(fp_line
			(start -0.67945 -0.305054)
			(end -0.12065 -0.305054)
			(stroke
				(width 0.1)
				(type default)
			)
			(layer "F.Fab")
		)
		(pad "1" smd circle
			(at -0.40005 0 180)
			(size 0 0)
			(layers "F.Cu" "F.Mask" "F.Paste")
			(net "GND")
		)
		(pad "2" smd circle
			(at 0.40005 0 180)
			(size 0 0)
			(layers "F.Cu" "F.Mask" "F.Paste")
			(net "UART_BIC_DEBUG_R_RX")
		)
	)
	(footprint ""
		(layer "F.Cu")
		(at 315.493908 -35.264852)
		(property "Reference" "R5692"
			(at 0 0 0)
			(layer "F.SilkS")
			(hide yes)
			(effects
				(font
					(size 1.27 1.27)
				)
			)
		)
		(property "Value" ""
			(at 0 0 0)
			(layer "F.Fab")
			(effects
				(font
					(size 1.27 1.27)
				)
			)
		)
		(duplicate_pad_numbers_are_jumpers no)
		(fp_line
			(start -0.7874 -0.4064)
			(end 0.7874 -0.4064)
			(stroke
				(width 0.1524)
				(type default)
			)
			(layer "F.SilkS")
		)
		(fp_line
			(start -0.7874 0.4064)
			(end -0.7874 -0.4064)
			(stroke
				(width 0.1524)
				(type default)
			)
			(layer "F.SilkS")
		)
		(fp_line
			(start 0.7874 -0.4064)
			(end 0.7874 0.4064)
			(stroke
				(width 0.1524)
				(type default)
			)
			(layer "F.SilkS")
		)
		(fp_line
			(start 0.7874 0.4064)
			(end -0.7874 0.4064)
			(stroke
				(width 0.1524)
				(type default)
			)
			(layer "F.SilkS")
		)
		(fp_line
			(start -0.67945 -0.305054)
			(end -0.12065 -0.305054)
			(stroke
				(width 0.1)
				(type default)
			)
			(layer "F.Fab")
		)
		(fp_line
			(start -0.67945 0.3048)
			(end -0.67945 -0.305054)
			(stroke
				(width 0.1)
				(type default)
			)
			(layer "F.Fab")
		)
		(fp_line
			(start -0.12065 -0.305054)
			(end -0.12065 -0.2794)
			(stroke
				(width 0.1)
				(type default)
			)
			(layer "F.Fab")
		)
		(fp_line
			(start -0.12065 -0.2794)
			(end 0.12065 -0.2794)
			(stroke
				(width 0.1)
				(type default)
			)
			(layer "F.Fab")
		)
		(fp_line
			(start -0.12065 0.2794)
			(end -0.12065 0.3048)
			(stroke
				(width 0.1)
				(type default)
			)
			(layer "F.Fab")
		)
		(fp_line
			(start -0.12065 0.3048)
			(end -0.67945 0.3048)
			(stroke
				(width 0.1)
				(type default)
			)
			(layer "F.Fab")
		)
		(fp_line
			(start 0.120396 0.2794)
			(end -0.12065 0.2794)
			(stroke
				(width 0.1)
				(type default)
			)
			(layer "F.Fab")
		)
		(fp_line
			(start 0.120396 0.3048)
			(end 0.120396 0.2794)
			(stroke
				(width 0.1)
				(type default)
			)
			(layer "F.Fab")
		)
		(fp_line
			(start 0.12065 -0.3048)
			(end 0.67945 -0.3048)
			(stroke
				(width 0.1)
				(type default)
			)
			(layer "F.Fab")
		)
		(fp_line
			(start 0.12065 -0.2794)
			(end 0.12065 -0.3048)
			(stroke
				(width 0.1)
				(type default)
			)
			(layer "F.Fab")
		)
		(fp_line
			(start 0.67945 -0.3048)
			(end 0.67945 0.3048)
			(stroke
				(width 0.1)
				(type default)
			)
			(layer "F.Fab")
		)
		(fp_line
			(start 0.67945 0.3048)
			(end 0.120396 0.3048)
			(stroke
				(width 0.1)
				(type default)
			)
			(layer "F.Fab")
		)
		(pad "1" smd circle
			(at -0.40005 0)
			(size 0 0)
			(layers "F.Cu" "F.Mask" "F.Paste")
			(net "RST_SMB_SSD11_ISO_N")
		)
		(pad "2" smd circle
			(at 0.40005 0)
			(size 0 0)
			(layers "F.Cu" "F.Mask" "F.Paste")
			(net "GND")
		)
	)
	(footprint ""
		(layer "F.Cu")
		(at 312.739532 -158.219648)
		(property "Reference" "R263"
			(at 0 0 0)
			(layer "F.SilkS")
			(hide yes)
			(effects
				(font
					(size 1.27 1.27)
				)
			)
		)
		(property "Value" ""
			(at 0 0 0)
			(layer "F.Fab")
			(effects
				(font
					(size 1.27 1.27)
				)
			)
		)
		(duplicate_pad_numbers_are_jumpers no)
		(fp_line
			(start -0.7874 -0.4064)
			(end 0.7874 -0.4064)
			(stroke
				(width 0.1524)
				(type default)
			)
			(layer "F.SilkS")
		)
		(fp_line
			(start -0.7874 0.4064)
			(end -0.7874 -0.4064)
			(stroke
				(width 0.1524)
				(type default)
			)
			(layer "F.SilkS")
		)
		(fp_line
			(start 0.7874 -0.4064)
			(end 0.7874 0.4064)
			(stroke
				(width 0.1524)
				(type default)
			)
			(layer "F.SilkS")
		)
		(fp_line
			(start 0.7874 0.4064)
			(end -0.7874 0.4064)
			(stroke
				(width 0.1524)
				(type default)
			)
			(layer "F.SilkS")
		)
		(fp_line
			(start -0.67945 -0.305054)
			(end -0.12065 -0.305054)
			(stroke
				(width 0.1)
				(type default)
			)
			(layer "F.Fab")
		)
		(fp_line
			(start -0.67945 0.3048)
			(end -0.67945 -0.305054)
			(stroke
				(width 0.1)
				(type default)
			)
			(layer "F.Fab")
		)
		(fp_line
			(start -0.12065 -0.305054)
			(end -0.12065 -0.2794)
			(stroke
				(width 0.1)
				(type default)
			)
			(layer "F.Fab")
		)
		(fp_line
			(start -0.12065 -0.2794)
			(end 0.12065 -0.2794)
			(stroke
				(width 0.1)
				(type default)
			)
			(layer "F.Fab")
		)
		(fp_line
			(start -0.12065 0.2794)
			(end -0.12065 0.3048)
			(stroke
				(width 0.1)
				(type default)
			)
			(layer "F.Fab")
		)
		(fp_line
			(start -0.12065 0.3048)
			(end -0.67945 0.3048)
			(stroke
				(width 0.1)
				(type default)
			)
			(layer "F.Fab")
		)
		(fp_line
			(start 0.120396 0.2794)
			(end -0.12065 0.2794)
			(stroke
				(width 0.1)
				(type default)
			)
			(layer "F.Fab")
		)
		(fp_line
			(start 0.120396 0.3048)
			(end 0.120396 0.2794)
			(stroke
				(width 0.1)
				(type default)
			)
			(layer "F.Fab")
		)
		(fp_line
			(start 0.12065 -0.3048)
			(end 0.67945 -0.3048)
			(stroke
				(width 0.1)
				(type default)
			)
			(layer "F.Fab")
		)
		(fp_line
			(start 0.12065 -0.2794)
			(end 0.12065 -0.3048)
			(stroke
				(width 0.1)
				(type default)
			)
			(layer "F.Fab")
		)
		(fp_line
			(start 0.67945 -0.3048)
			(end 0.67945 0.3048)
			(stroke
				(width 0.1)
				(type default)
			)
			(layer "F.Fab")
		)
		(fp_line
			(start 0.67945 0.3048)
			(end 0.120396 0.3048)
			(stroke
				(width 0.1)
				(type default)
			)
			(layer "F.Fab")
		)
		(pad "1" smd circle
			(at -0.40005 0)
			(size 0 0)
			(layers "F.Cu" "F.Mask" "F.Paste")
			(net "PRSNTB3_NIC5_N")
		)
		(pad "2" smd circle
			(at 0.40005 0)
			(size 0 0)
			(layers "F.Cu" "F.Mask" "F.Paste")
			(net "P3V3_AUX")
		)
	)
	(footprint ""
		(layer "F.Cu")
		(at 194.343782 -44.87291)
		(property "Reference" "R572"
			(at 0 0 0)
			(layer "F.SilkS")
			(hide yes)
			(effects
				(font
					(size 1.27 1.27)
				)
			)
		)
		(property "Value" ""
			(at 0 0 0)
			(layer "F.Fab")
			(effects
				(font
					(size 1.27 1.27)
				)
			)
		)
		(duplicate_pad_numbers_are_jumpers no)
		(fp_line
			(start -0.7874 -0.4064)
			(end 0.7874 -0.4064)
			(stroke
				(width 0.1524)
				(type default)
			)
			(layer "F.SilkS")
		)
		(fp_line
			(start -0.7874 0.4064)
			(end -0.7874 -0.4064)
			(stroke
				(width 0.1524)
				(type default)
			)
			(layer "F.SilkS")
		)
		(fp_line
			(start 0.7874 -0.4064)
			(end 0.7874 0.4064)
			(stroke
				(width 0.1524)
				(type default)
			)
			(layer "F.SilkS")
		)
		(fp_line
			(start 0.7874 0.4064)
			(end -0.7874 0.4064)
			(stroke
				(width 0.1524)
				(type default)
			)
			(layer "F.SilkS")
		)
		(fp_line
			(start -0.67945 -0.305054)
			(end -0.12065 -0.305054)
			(stroke
				(width 0.1)
				(type default)
			)
			(layer "F.Fab")
		)
		(fp_line
			(start -0.67945 0.3048)
			(end -0.67945 -0.305054)
			(stroke
				(width 0.1)
				(type default)
			)
			(layer "F.Fab")
		)
		(fp_line
			(start -0.12065 -0.305054)
			(end -0.12065 -0.2794)
			(stroke
				(width 0.1)
				(type default)
			)
			(layer "F.Fab")
		)
		(fp_line
			(start -0.12065 -0.2794)
			(end 0.12065 -0.2794)
			(stroke
				(width 0.1)
				(type default)
			)
			(layer "F.Fab")
		)
		(fp_line
			(start -0.12065 0.2794)
			(end -0.12065 0.3048)
			(stroke
				(width 0.1)
				(type default)
			)
			(layer "F.Fab")
		)
		(fp_line
			(start -0.12065 0.3048)
			(end -0.67945 0.3048)
			(stroke
				(width 0.1)
				(type default)
			)
			(layer "F.Fab")
		)
		(fp_line
			(start 0.120396 0.2794)
			(end -0.12065 0.2794)
			(stroke
				(width 0.1)
				(type default)
			)
			(layer "F.Fab")
		)
		(fp_line
			(start 0.120396 0.3048)
			(end 0.120396 0.2794)
			(stroke
				(width 0.1)
				(type default)
			)
			(layer "F.Fab")
		)
		(fp_line
			(start 0.12065 -0.3048)
			(end 0.67945 -0.3048)
			(stroke
				(width 0.1)
				(type default)
			)
			(layer "F.Fab")
		)
		(fp_line
			(start 0.12065 -0.2794)
			(end 0.12065 -0.3048)
			(stroke
				(width 0.1)
				(type default)
			)
			(layer "F.Fab")
		)
		(fp_line
			(start 0.67945 -0.3048)
			(end 0.67945 0.3048)
			(stroke
				(width 0.1)
				(type default)
			)
			(layer "F.Fab")
		)
		(fp_line
			(start 0.67945 0.3048)
			(end 0.120396 0.3048)
			(stroke
				(width 0.1)
				(type default)
			)
			(layer "F.Fab")
		)
		(pad "1" smd circle
			(at -0.40005 0)
			(size 0 0)
			(layers "F.Cu" "F.Mask" "F.Paste")
			(net "SSD6_ADC_A0")
		)
		(pad "2" smd circle
			(at 0.40005 0)
			(size 0 0)
			(layers "F.Cu" "F.Mask" "F.Paste")
			(net "P3V3_AUX")
		)
	)
)
